(kicad_pcb
	(version 20260206)
	(generator "pcbnew")
	(generator_version "10.0")
	(general
		(thickness 1.6)
		(legacy_teardrops no)
	)
	(paper "A4")
	(title_block
		(title "peb — Lightning_PEB_BRD.brd")
		(comment 1 "Lightning (Wiwynn / Facebook NVMe JBOF) / footprints 342-348 of 2563")
	)
	(layers
		(0 "F.Cu" signal "TOP")
		(4 "In1.Cu" signal "L2GND")
		(6 "In2.Cu" signal "L3")
		(8 "In3.Cu" signal "L4VCC")
		(10 "In4.Cu" signal "L5VCC")
		(12 "In5.Cu" signal "L6")
		(14 "In6.Cu" signal "L7GND")
		(2 "B.Cu" signal "BOTTOM")
		(9 "F.Adhes" user "F.Adhesive")
		(11 "B.Adhes" user "B.Adhesive")
		(13 "F.Paste" user "Package Geometry/Pastemask Top")
		(15 "B.Paste" user "Package Geometry/Pastemask Bottom")
		(5 "F.SilkS" user "Ref Des/Silkscreen Top")
		(7 "B.SilkS" user "Ref Des/Silkscreen Bottom")
		(1 "F.Mask" user "Board Geometry/Soldermask Top")
		(3 "B.Mask" user "Board Geometry/Soldermask Bottom")
		(17 "Dwgs.User" user "User.Drawings")
		(19 "Cmts.User" user "User.Comments")
		(21 "Eco1.User" user "User.Eco1")
		(23 "Eco2.User" user "User.Eco2")
		(25 "Edge.Cuts" user "Board Geometry/Outline")
		(27 "Margin" user)
		(31 "F.CrtYd" user "Package Geometry/Place Bound Top")
		(29 "B.CrtYd" user "Package Geometry/Place Bound Bottom")
		(35 "F.Fab" user "Ref Des/Assembly Top")
		(33 "B.Fab" user "Ref Des/Assembly Bottom")
	)
	(footprint ""
		(layer "F.Cu")
		(at 46.186852 -32.819594)
		(property "Reference" "R545"
			(at 0 0 0)
			(layer "F.SilkS")
			(hide yes)
			(effects
				(font
					(size 1.27 1.27)
				)
			)
		)
		(property "Value" "0R3J-0-U-GP"
			(at -0.0254 -2.5146 0)
			(unlocked yes)
			(layer "F.Fab")
			(hide yes)
			(effects
				(font
					(size 1.016 1.016)
					(thickness 0.1524)
				)
			)
		)
		(property "Device Type" "R603H22"
			(at -0.0254 -4.0386 0)
			(unlocked yes)
			(layer "F.Fab")
			(hide yes)
			(effects
				(font
					(size 1.016 1.016)
					(thickness 0.1524)
				)
			)
		)
		(duplicate_pad_numbers_are_jumpers no)
		(fp_line
			(start -0.4826 0)
			(end -0.2032 0)
			(stroke
				(width 0.2032)
				(type default)
			)
			(layer "F.SilkS")
		)
		(fp_line
			(start 0.2032 0)
			(end 0.4826 0)
			(stroke
				(width 0.2032)
				(type default)
			)
			(layer "F.SilkS")
		)
		(fp_rect
			(start -0.5842 1.3335)
			(end 0.5842 -1.3335)
			(stroke
				(width 0)
				(type default)
			)
			(fill no)
			(layer "F.CrtYd")
		)
		(fp_rect
			(start -0.5842 1.3335)
			(end 0.5842 -1.3335)
			(stroke
				(width 0)
				(type default)
			)
			(fill no)
			(layer "F.Fab")
		)
		(pad "1" smd custom
			(at 0 -0.762)
			(size 0.2159 0.2159)
			(layers "F.Cu" "F.Mask" "F.Paste")
			(net "AGND_USB")
			(options
				(clearance outline)
				(anchor circle)
			)
			(primitives
				(gr_poly
					(pts
						(arc
							(start -0.3302 -0.4318)
							(mid -0.402042 -0.402042)
							(end -0.4318 -0.3302)
						)
						(arc
							(start -0.4318 0.3302)
							(mid -0.402042 0.402042)
							(end -0.3302 0.4318)
						)
						(arc
							(start 0.3302 0.4318)
							(mid 0.402042 0.402042)
							(end 0.4318 0.3302)
						)
						(arc
							(start 0.4318 -0.3302)
							(mid 0.402042 -0.402042)
							(end 0.3302 -0.4318)
						)
					)
					(width 0)
					(fill yes)
				)
			)
		)
		(pad "2" smd custom
			(at 0 0.762)
			(size 0.2159 0.2159)
			(layers "F.Cu" "F.Mask" "F.Paste")
			(net "GND")
			(options
				(clearance outline)
				(anchor circle)
			)
			(primitives
				(gr_poly
					(pts
						(arc
							(start -0.3302 -0.4318)
							(mid -0.402042 -0.402042)
							(end -0.4318 -0.3302)
						)
						(arc
							(start -0.4318 0.3302)
							(mid -0.402042 0.402042)
							(end -0.3302 0.4318)
						)
						(arc
							(start 0.3302 0.4318)
							(mid 0.402042 0.402042)
							(end 0.4318 0.3302)
						)
						(arc
							(start 0.4318 -0.3302)
							(mid 0.402042 -0.402042)
							(end 0.3302 -0.4318)
						)
					)
					(width 0)
					(fill yes)
				)
			)
		)
	)
	(footprint ""
		(layer "F.Cu")
		(at 337.852512 -172.432218)
		(property "Reference" "R7939"
			(at 0 0 0)
			(layer "F.SilkS")
			(hide yes)
			(effects
				(font
					(size 1.27 1.27)
				)
			)
		)
		(property "Value" "0R2J-2-GP"
			(at 0.064008 -3.993896 0)
			(unlocked yes)
			(layer "F.Fab")
			(hide yes)
			(effects
				(font
					(size 1.016 1.016)
					(thickness 0.1524)
				)
			)
		)
		(property "Device Type" "R402H16"
			(at 0.064008 -5.517896 0)
			(unlocked yes)
			(layer "F.Fab")
			(hide yes)
			(effects
				(font
					(size 1.016 1.016)
					(thickness 0.1524)
				)
			)
		)
		(duplicate_pad_numbers_are_jumpers no)
		(fp_line
			(start -0.508 -0.9398)
			(end -0.508 0.9398)
			(stroke
				(width 0.1524)
				(type default)
			)
			(layer "F.SilkS")
		)
		(fp_line
			(start 0.508 -0.9398)
			(end -0.508 -0.9398)
			(stroke
				(width 0.1524)
				(type default)
			)
			(layer "F.SilkS")
		)
		(fp_rect
			(start -0.508 0.9398)
			(end 0.508 -0.9398)
			(stroke
				(width 0)
				(type default)
			)
			(fill no)
			(layer "F.CrtYd")
		)
		(fp_rect
			(start -0.508 0.9398)
			(end 0.508 -0.9398)
			(stroke
				(width 0)
				(type default)
			)
			(fill no)
			(layer "F.Fab")
		)
		(pad "1" smd custom
			(at 0 -0.4445)
			(size 0.1397 0.1397)
			(layers "F.Cu" "F.Mask" "F.Paste")
			(net "SSD_ATNLED#9")
			(options
				(clearance outline)
				(anchor circle)
			)
			(primitives
				(gr_poly
					(pts
						(arc
							(start -0.1778 -0.2794)
							(mid -0.249642 -0.249642)
							(end -0.2794 -0.1778)
						)
						(arc
							(start -0.2794 0.1778)
							(mid -0.249642 0.249642)
							(end -0.1778 0.2794)
						)
						(arc
							(start 0.1778 0.2794)
							(mid 0.249642 0.249642)
							(end 0.2794 0.1778)
						)
						(arc
							(start 0.2794 -0.1778)
							(mid 0.249642 -0.249642)
							(end 0.1778 -0.2794)
						)
					)
					(width 0)
					(fill yes)
				)
			)
		)
		(pad "2" smd custom
			(at 0 0.4445)
			(size 0.1397 0.1397)
			(layers "F.Cu" "F.Mask" "F.Paste")
			(net "SSD_ATNLED#9_R")
			(options
				(clearance outline)
				(anchor circle)
			)
			(primitives
				(gr_poly
					(pts
						(arc
							(start -0.1778 -0.2794)
							(mid -0.249642 -0.249642)
							(end -0.2794 -0.1778)
						)
						(arc
							(start -0.2794 0.1778)
							(mid -0.249642 0.249642)
							(end -0.1778 0.2794)
						)
						(arc
							(start 0.1778 0.2794)
							(mid 0.249642 0.249642)
							(end 0.2794 0.1778)
						)
						(arc
							(start 0.2794 -0.1778)
							(mid 0.249642 -0.249642)
							(end 0.1778 -0.2794)
						)
					)
					(width 0)
					(fill yes)
				)
			)
		)
	)
	(footprint ""
		(layer "F.Cu")
		(at 10.287 -105.156 90)
		(property "Reference" "PR72"
			(at 0 0 90)
			(layer "F.SilkS")
			(hide yes)
			(effects
				(font
					(size 1.27 1.27)
				)
			)
		)
		(property "Value" "0R3J-0-U-GP"
			(at -0.0254 -2.5146 90)
			(unlocked yes)
			(layer "F.Fab")
			(hide yes)
			(effects
				(font
					(size 1.016 1.016)
					(thickness 0.1524)
				)
			)
		)
		(property "Device Type" "R603H22"
			(at -0.0254 -4.0386 90)
			(unlocked yes)
			(layer "F.Fab")
			(hide yes)
			(effects
				(font
					(size 1.016 1.016)
					(thickness 0.1524)
				)
			)
		)
		(duplicate_pad_numbers_are_jumpers no)
		(fp_line
			(start 0.2032 0)
			(end 0.4826 0)
			(stroke
				(width 0.2032)
				(type default)
			)
			(layer "F.SilkS")
		)
		(fp_line
			(start -0.4826 0)
			(end -0.2032 0)
			(stroke
				(width 0.2032)
				(type default)
			)
			(layer "F.SilkS")
		)
		(fp_rect
			(start -0.5842 1.3335)
			(end 0.5842 -1.3335)
			(stroke
				(width 0)
				(type default)
			)
			(fill no)
			(layer "F.CrtYd")
		)
		(fp_rect
			(start -0.5842 1.3335)
			(end 0.5842 -1.3335)
			(stroke
				(width 0)
				(type default)
			)
			(fill no)
			(layer "F.Fab")
		)
		(pad "1" smd custom
			(at 0 -0.762 90)
			(size 0.2159 0.2159)
			(layers "F.Cu" "F.Mask" "F.Paste")
			(net "PWRGD_P1V538_STBY")
			(options
				(clearance outline)
				(anchor circle)
			)
			(primitives
				(gr_poly
					(pts
						(arc
							(start -0.3302 -0.4318)
							(mid -0.402042 -0.402042)
							(end -0.4318 -0.3302)
						)
						(arc
							(start -0.4318 0.3302)
							(mid -0.402042 0.402042)
							(end -0.3302 0.4318)
						)
						(arc
							(start 0.3302 0.4318)
							(mid 0.402042 0.402042)
							(end 0.4318 0.3302)
						)
						(arc
							(start 0.4318 -0.3302)
							(mid 0.402042 -0.402042)
							(end 0.3302 -0.4318)
						)
					)
					(width 0)
					(fill yes)
				)
			)
		)
		(pad "2" smd custom
			(at 0 0.762 90)
			(size 0.2159 0.2159)
			(layers "F.Cu" "F.Mask" "F.Paste")
			(net "VR_P1V26_STBY_EN_R")
			(options
				(clearance outline)
				(anchor circle)
			)
			(primitives
				(gr_poly
					(pts
						(arc
							(start -0.3302 -0.4318)
							(mid -0.402042 -0.402042)
							(end -0.4318 -0.3302)
						)
						(arc
							(start -0.4318 0.3302)
							(mid -0.402042 0.402042)
							(end -0.3302 0.4318)
						)
						(arc
							(start 0.3302 0.4318)
							(mid 0.402042 0.402042)
							(end 0.4318 0.3302)
						)
						(arc
							(start 0.4318 -0.3302)
							(mid 0.402042 -0.402042)
							(end 0.3302 -0.4318)
						)
					)
					(width 0)
					(fill yes)
				)
			)
		)
	)
	(footprint ""
		(layer "F.Cu")
		(at 199.6186 -18.8214 90)
		(property "Reference" "R706"
			(at 0 0 90)
			(layer "F.SilkS")
			(hide yes)
			(effects
				(font
					(size 1.27 1.27)
				)
			)
		)
		(property "Value" "4K7R2F-GP"
			(at 0.064008 -3.993896 90)
			(unlocked yes)
			(layer "F.Fab")
			(hide yes)
			(effects
				(font
					(size 1.016 1.016)
					(thickness 0.1524)
				)
			)
		)
		(property "Device Type" "R402H16"
			(at 0.064008 -5.517896 90)
			(unlocked yes)
			(layer "F.Fab")
			(hide yes)
			(effects
				(font
					(size 1.016 1.016)
					(thickness 0.1524)
				)
			)
		)
		(duplicate_pad_numbers_are_jumpers no)
		(fp_line
			(start 0.508 -0.9398)
			(end -0.508 -0.9398)
			(stroke
				(width 0.1524)
				(type default)
			)
			(layer "F.SilkS")
		)
		(fp_line
			(start -0.508 -0.9398)
			(end -0.508 0.9398)
			(stroke
				(width 0.1524)
				(type default)
			)
			(layer "F.SilkS")
		)
		(fp_rect
			(start -0.508 0.9398)
			(end 0.508 -0.9398)
			(stroke
				(width 0)
				(type default)
			)
			(fill no)
			(layer "F.CrtYd")
		)
		(fp_rect
			(start -0.508 0.9398)
			(end 0.508 -0.9398)
			(stroke
				(width 0)
				(type default)
			)
			(fill no)
			(layer "F.Fab")
		)
		(pad "1" smd custom
			(at 0 -0.4445 90)
			(size 0.1397 0.1397)
			(layers "F.Cu" "F.Mask" "F.Paste")
			(net "MINISAS_CN16_B_I2C_INT#")
			(options
				(clearance outline)
				(anchor circle)
			)
			(primitives
				(gr_poly
					(pts
						(arc
							(start -0.1778 -0.2794)
							(mid -0.249642 -0.249642)
							(end -0.2794 -0.1778)
						)
						(arc
							(start -0.2794 0.1778)
							(mid -0.249642 0.249642)
							(end -0.1778 0.2794)
						)
						(arc
							(start 0.1778 0.2794)
							(mid 0.249642 0.249642)
							(end 0.2794 0.1778)
						)
						(arc
							(start 0.2794 -0.1778)
							(mid 0.249642 -0.249642)
							(end 0.1778 -0.2794)
						)
					)
					(width 0)
					(fill yes)
				)
			)
		)
		(pad "2" smd custom
			(at 0 0.4445 90)
			(size 0.1397 0.1397)
			(layers "F.Cu" "F.Mask" "F.Paste")
			(net "P3V3_STBY")
			(options
				(clearance outline)
				(anchor circle)
			)
			(primitives
				(gr_poly
					(pts
						(arc
							(start -0.1778 -0.2794)
							(mid -0.249642 -0.249642)
							(end -0.2794 -0.1778)
						)
						(arc
							(start -0.2794 0.1778)
							(mid -0.249642 0.249642)
							(end -0.1778 0.2794)
						)
						(arc
							(start 0.1778 0.2794)
							(mid 0.249642 0.249642)
							(end 0.2794 0.1778)
						)
						(arc
							(start 0.2794 -0.1778)
							(mid 0.249642 -0.249642)
							(end 0.1778 -0.2794)
						)
					)
					(width 0)
					(fill yes)
				)
			)
		)
	)
	(footprint ""
		(layer "F.Cu")
		(at 50.165 -145.296128)
		(property "Reference" "SR853"
			(at 0 0 0)
			(layer "F.SilkS")
			(hide yes)
			(effects
				(font
					(size 1.27 1.27)
				)
			)
		)
		(property "Value" "4K75R2F-1-GP"
			(at 0.064008 -3.993896 0)
			(unlocked yes)
			(layer "F.Fab")
			(hide yes)
			(effects
				(font
					(size 1.016 1.016)
					(thickness 0.1524)
				)
			)
		)
		(property "Device Type" "R402H16"
			(at 0.064008 -5.517896 0)
			(unlocked yes)
			(layer "F.Fab")
			(hide yes)
			(effects
				(font
					(size 1.016 1.016)
					(thickness 0.1524)
				)
			)
		)
		(duplicate_pad_numbers_are_jumpers no)
		(fp_line
			(start -0.508 -0.9398)
			(end -0.508 0.9398)
			(stroke
				(width 0.1524)
				(type default)
			)
			(layer "F.SilkS")
		)
		(fp_line
			(start 0.508 -0.9398)
			(end -0.508 -0.9398)
			(stroke
				(width 0.1524)
				(type default)
			)
			(layer "F.SilkS")
		)
		(fp_rect
			(start -0.508 0.9398)
			(end 0.508 -0.9398)
			(stroke
				(width 0)
				(type default)
			)
			(fill no)
			(layer "F.CrtYd")
		)
		(fp_rect
			(start -0.508 0.9398)
			(end 0.508 -0.9398)
			(stroke
				(width 0)
				(type default)
			)
			(fill no)
			(layer "F.Fab")
		)
		(pad "1" smd custom
			(at 0 -0.4445)
			(size 0.1397 0.1397)
			(layers "F.Cu" "F.Mask" "F.Paste")
			(net "P3V3_STBY")
			(options
				(clearance outline)
				(anchor circle)
			)
			(primitives
				(gr_poly
					(pts
						(arc
							(start -0.1778 -0.2794)
							(mid -0.249642 -0.249642)
							(end -0.2794 -0.1778)
						)
						(arc
							(start -0.2794 0.1778)
							(mid -0.249642 0.249642)
							(end -0.1778 0.2794)
						)
						(arc
							(start 0.1778 0.2794)
							(mid 0.249642 0.249642)
							(end 0.2794 0.1778)
						)
						(arc
							(start 0.2794 -0.1778)
							(mid 0.249642 -0.249642)
							(end 0.1778 -0.2794)
						)
					)
					(width 0)
					(fill yes)
				)
			)
		)
		(pad "2" smd custom
			(at 0 0.4445)
			(size 0.1397 0.1397)
			(layers "F.Cu" "F.Mask" "F.Paste")
			(net "BMC_FW_DET_BOARD_VER_2")
			(options
				(clearance outline)
				(anchor circle)
			)
			(primitives
				(gr_poly
					(pts
						(arc
							(start -0.1778 -0.2794)
							(mid -0.249642 -0.249642)
							(end -0.2794 -0.1778)
						)
						(arc
							(start -0.2794 0.1778)
							(mid -0.249642 0.249642)
							(end -0.1778 0.2794)
						)
						(arc
							(start 0.1778 0.2794)
							(mid 0.249642 0.249642)
							(end 0.2794 0.1778)
						)
						(arc
							(start 0.2794 -0.1778)
							(mid 0.249642 -0.249642)
							(end 0.1778 -0.2794)
						)
					)
					(width 0)
					(fill yes)
				)
			)
		)
	)
	(footprint ""
		(layer "F.Cu")
		(at 131.252468 -54.760876 180)
		(property "Reference" "SCN9"
			(at 0 0 180)
			(layer "F.SilkS")
			(hide yes)
			(effects
				(font
					(size 1.27 1.27)
				)
			)
		)
		(property "Value" "JWT-CON4-S24-GP"
			(at -7.3787 1.4351 180)
			(unlocked yes)
			(layer "F.Fab")
			(hide yes)
			(effects
				(font
					(size 1.016 1.016)
					(thickness 0.1524)
				)
			)
		)
		(property "Device Type" "A2541WV0-1QX4PA-6T"
			(at -7.3787 -0.0889 180)
			(unlocked yes)
			(layer "F.Fab")
			(hide yes)
			(effects
				(font
					(size 1.016 1.016)
					(thickness 0.1524)
				)
			)
		)
		(duplicate_pad_numbers_are_jumpers no)
		(fp_line
			(start 5.334 1.524)
			(end 5.334 -1.524)
			(stroke
				(width 0.1524)
				(type default)
			)
			(layer "F.SilkS")
		)
		(fp_line
			(start 5.334 -1.524)
			(end -5.334 -1.524)
			(stroke
				(width 0.1524)
				(type default)
			)
			(layer "F.SilkS")
		)
		(fp_line
			(start -4.191 -1.651)
			(end -5.461 -1.651)
			(stroke
				(width 0.4064)
				(type default)
			)
			(layer "F.SilkS")
		)
		(fp_line
			(start -5.334 1.524)
			(end 5.334 1.524)
			(stroke
				(width 0.1524)
				(type default)
			)
			(layer "F.SilkS")
		)
		(fp_line
			(start -5.334 -1.524)
			(end -5.334 1.524)
			(stroke
				(width 0.1524)
				(type default)
			)
			(layer "F.SilkS")
		)
		(fp_line
			(start -5.461 -1.651)
			(end -5.461 -0.381)
			(stroke
				(width 0.4064)
				(type default)
			)
			(layer "F.SilkS")
		)
		(fp_circle
			(center 3.81 0)
			(end 2.7432 0)
			(stroke
				(width 0.3048)
				(type default)
			)
			(fill no)
			(layer "F.SilkS")
		)
		(fp_circle
			(center 1.27 0)
			(end 0.2032 0)
			(stroke
				(width 0.3048)
				(type default)
			)
			(fill no)
			(layer "F.SilkS")
		)
		(fp_circle
			(center -1.27 0)
			(end -2.3368 0)
			(stroke
				(width 0.3048)
				(type default)
			)
			(fill no)
			(layer "F.SilkS")
		)
		(fp_circle
			(center -3.81 0)
			(end -4.8768 0)
			(stroke
				(width 0.3048)
				(type default)
			)
			(fill no)
			(layer "F.SilkS")
		)
		(fp_rect
			(start -5.08 1.27)
			(end 5.08 -1.27)
			(stroke
				(width 0)
				(type default)
			)
			(fill no)
			(layer "F.CrtYd")
		)
		(fp_poly
			(pts
				(xy -5.588 1.778) (xy -5.588 -1.778) (xy 5.588 -1.778) (xy 5.588 1.2573) (xy 5.08 1.2573) (xy 5.08 -1.27)
				(xy -5.08 -1.27) (xy -5.08 1.27) (xy 5.588 1.27) (xy 5.588 1.778)
			)
			(stroke
				(width 0)
				(type default)
			)
			(fill no)
			(layer "F.CrtYd")
		)
		(fp_rect
			(start -5.588 1.778)
			(end 5.588 -1.778)
			(stroke
				(width 0)
				(type default)
			)
			(fill no)
			(layer "F.Fab")
		)
		(pad "1" thru_hole circle
			(at -3.81 0 180)
			(size 1.4224 1.4224)
			(drill 1.016)
			(layers "*.Cu" "*.Mask")
			(remove_unused_layers no)
			(net "P5V_STBY")
			(clearance 0.1524)
			(thermal_gap 0.1524)
		)
		(pad "2" thru_hole circle
			(at -1.27 0 180)
			(size 1.4224 1.4224)
			(drill 1.016)
			(layers "*.Cu" "*.Mask")
			(remove_unused_layers no)
			(net "PMC_R_TXD5")
			(clearance 0.1524)
			(thermal_gap 0.1524)
		)
		(pad "3" thru_hole circle
			(at 1.27 0 180)
			(size 1.4224 1.4224)
			(drill 1.016)
			(layers "*.Cu" "*.Mask")
			(remove_unused_layers no)
			(net "PMC_R_RXD5")
			(clearance 0.1524)
			(thermal_gap 0.1524)
		)
		(pad "4" thru_hole circle
			(at 3.81 0 180)
			(size 1.4224 1.4224)
			(drill 1.016)
			(layers "*.Cu" "*.Mask")
			(remove_unused_layers no)
			(net "GND")
			(clearance 0.1524)
			(thermal_gap 0.1524)
		)
	)
	(footprint ""
		(layer "F.Cu")
		(at 139.408154 -212.420454 180)
		(property "Reference" "C343"
			(at 0 0 180)
			(layer "F.SilkS")
			(hide yes)
			(effects
				(font
					(size 1.27 1.27)
				)
			)
		)
		(property "Value" "SCD22U10V2KX-1GP"
			(at 1.1811 -2.7051 180)
			(unlocked yes)
			(layer "F.Fab")
			(hide yes)
			(effects
				(font
					(size 1.016 1.016)
					(thickness 0.1524)
				)
			)
		)
		(property "Device Type" "C402H22"
			(at 1.1811 -4.2291 180)
			(unlocked yes)
			(layer "F.Fab")
			(hide yes)
			(effects
				(font
					(size 1.016 1.016)
					(thickness 0.1524)
				)
			)
		)
		(duplicate_pad_numbers_are_jumpers no)
		(fp_rect
			(start -0.4318 0.9525)
			(end 0.4318 -0.9525)
			(stroke
				(width 0)
				(type default)
			)
			(fill no)
			(layer "F.CrtYd")
		)
		(fp_rect
			(start -0.4318 0.9525)
			(end 0.4318 -0.9525)
			(stroke
				(width 0)
				(type default)
			)
			(fill no)
			(layer "F.Fab")
		)
		(pad "1" smd custom
			(at 0 -0.4445 180)
			(size 0.1524 0.1524)
			(layers "F.Cu" "F.Mask" "F.Paste")
			(net "PCIE_TX_CAP_N59")
			(options
				(clearance outline)
				(anchor circle)
			)
			(primitives
				(gr_poly
					(pts
						(arc
							(start 0.3048 -0.2032)
							(mid 0.275042 -0.275042)
							(end 0.2032 -0.3048)
						)
						(arc
							(start -0.2032 -0.3048)
							(mid -0.275042 -0.275042)
							(end -0.3048 -0.2032)
						)
						(arc
							(start -0.3048 0.2032)
							(mid -0.275042 0.275042)
							(end -0.2032 0.3048)
						)
						(arc
							(start 0.2032 0.3048)
							(mid 0.275042 0.275042)
							(end 0.3048 0.2032)
						)
					)
					(width 0)
					(fill yes)
				)
			)
		)
		(pad "2" smd custom
			(at 0 0.4445 180)
			(size 0.1524 0.1524)
			(layers "F.Cu" "F.Mask" "F.Paste")
			(net "PCIE_TX_N59")
			(options
				(clearance outline)
				(anchor circle)
			)
			(primitives
				(gr_poly
					(pts
						(arc
							(start 0.3048 -0.2032)
							(mid 0.275042 -0.275042)
							(end 0.2032 -0.3048)
						)
						(arc
							(start -0.2032 -0.3048)
							(mid -0.275042 -0.275042)
							(end -0.3048 -0.2032)
						)
						(arc
							(start -0.3048 0.2032)
							(mid -0.275042 0.275042)
							(end -0.2032 0.3048)
						)
						(arc
							(start 0.2032 0.3048)
							(mid 0.275042 0.275042)
							(end 0.3048 0.2032)
						)
					)
					(width 0)
					(fill yes)
				)
			)
		)
	)
)
